FILE_TYPE = CONNECTIVITY;
{Allegro Design Entry HDL 17.2-2016 S081 (4005846) 1/11/2022}
"PAGE_NUMBER" = 75;
0"NC";
1"PVDD18_S5_P1\g";
2"CLK_CPU1_RTCCLK";
3"PD_ESPI_CPU0_CLK2";
4"CLK_ESPI_CPU0_CLK1";
5"CLK_CPU0_RTCCLK";
6"CLK_ESPI_CPU0_CLK1";
7"CLK_CPU0_RTCCLK";
8"PD_ESPI_CPU0_CLK2";
9"CPU0_ROM_TYPE_SELECT";
10"CPU0_ROM_TYPE_SELECT";
11"UART_CPU0_SCM_UART1_TX";
12"UART_CPU0_SCM_UART1_TX";
13"PD_ESPI_CPU1_CLK2";
14"SPI_CPU1_CLK";
15"CLK_CPU1_RTCCLK";
16"PD_ESPI_CPU1_CLK2";
17"SPI_CPU1_CLK";
18"GND\g";
19"PVDD18_S5_P0\g";
20"GND\g";
%"Q_RES"
"1","(-8650,3600)","0","pure_quanta","I12";
;
LOCATION"R751"
$SEC"1"
CDS_SEC"1"
MATERIAL"CHIP"
TOLERANCE"5%"
VALUE"10K"
CDS_LIB"pure_quanta"
WATTAGE"1/16W"
PART_NUMBER"TMP_QCS31002JB28"
PACK_TYPE"0402LF";
"B"
$PN"2"5;
"A"
$PN"1"18;
%"UNIVERSAL_GND"
"1","(-8950,3225)","0","pure_quanta_power","I15";
;
CDS_LIB"pure_quanta_power"
HDL_POWER"GND";
"A"18;
%"UNIVERSAL_POWER"
"1","(-8950,5950)","0","pure_quanta_power","I39";
;
HDL_POWER"PVDD18_S5_P0"
CDS_LIB"pure_quanta_power";
"A"19;
%"Q_RES"
"1","(-8650,5450)","0","pure_quanta","I41";
;
LOCATION"R729"
$SEC"1"
CDS_SEC"1"
MATERIAL"EMPTY"
TOLERANCE"5%"
VALUE"10K"
CDS_LIB"pure_quanta"
WATTAGE"1/16W"
PART_NUMBER"TMP_QCS31002JB28"
PACK_TYPE"0402LF";
"B"
$PN"2"11;
"A"
$PN"1"19;
%"Q_RES"
"1","(-8625,5175)","0","pure_quanta","I43";
;
LOCATION"R737"
$SEC"1"
CDS_SEC"1"
MATERIAL"CHIP"
TOLERANCE"5%"
VALUE"10K"
CDS_LIB"pure_quanta"
WATTAGE"1/16W"
PART_NUMBER"TMP_QCS31002JB28"
PACK_TYPE"0402LF";
"B"
$PN"2"10;
"A"
$PN"1"19;
%"Q_RES"
"1","(-8625,4800)","0","pure_quanta","I44";
;
LOCATION"R740"
$SEC"1"
CDS_SEC"1"
MATERIAL"EMPTY"
TOLERANCE"5%"
VALUE"10K"
CDS_LIB"pure_quanta"
WATTAGE"1/16W"
PART_NUMBER"TMP_QCS31002JB28"
PACK_TYPE"0402LF";
"B"
$PN"2"7;
"A"
$PN"1"19;
%"Q_RES"
"1","(-8625,4925)","0","pure_quanta","I45";
;
LOCATION"R739"
$SEC"1"
CDS_SEC"1"
MATERIAL"EMPTY"
TOLERANCE"5%"
VALUE"10K"
CDS_LIB"pure_quanta"
WATTAGE"1/16W"
PART_NUMBER"TMP_QCS31002JB28"
PACK_TYPE"0402LF";
"B"
$PN"2"6;
"A"
$PN"1"19;
%"Q_RES"
"1","(-8625,4550)","0","pure_quanta","I46";
;
LOCATION"R742"
$SEC"1"
CDS_SEC"1"
MATERIAL"EMPTY"
TOLERANCE"5%"
VALUE"10K"
CDS_LIB"pure_quanta"
WATTAGE"1/16W"
PART_NUMBER"TMP_QCS31002JB28"
PACK_TYPE"0402LF";
"B"
$PN"2"8;
"A"
$PN"1"19;
%"Q_RES"
"1","(-8650,3725)","0","pure_quanta","I74";
;
LOCATION"R750"
$SEC"1"
CDS_SEC"1"
MATERIAL"CHIP"
TOLERANCE"1%"
VALUE"30K"
CDS_LIB"pure_quanta"
WATTAGE"1/16W"
PART_NUMBER"CS33002FB13"
PACK_TYPE"0402LF";
"B"
$PN"2"4;
"A"
$PN"1"18;
%"Q_RES"
"1","(-8650,3350)","0","pure_quanta","I75";
;
LOCATION"R753"
$SEC"1"
CDS_SEC"1"
MATERIAL"CHIP"
TOLERANCE"5%"
VALUE"10K"
CDS_LIB"pure_quanta"
WATTAGE"1/16W"
PART_NUMBER"TMP_QCS31002JB28"
PACK_TYPE"0402LF";
"B"
$PN"2"3;
"A"
$PN"1"18;
%"Q_RES"
"1","(-8650,4250)","0","pure_quanta","I8";
;
LOCATION"R747"
$SEC"1"
CDS_SEC"1"
MATERIAL"CHIP"
TOLERANCE"5%"
VALUE"1K"
CDS_LIB"pure_quanta"
WATTAGE"1/16W"
PART_NUMBER"TMP_QCS21002JB34"
PACK_TYPE"0402LF";
"B"
$PN"2"12;
"A"
$PN"1"18;
%"Q_RES"
"1","(-3950,5550)","0","pure_quanta","I87";
;
LOCATION"R730"
$SEC"1"
CDS_SEC"1"
TOLERANCE"5%"
VALUE"10K"
MATERIAL"CHIP"
PACK_TYPE"0402LF"
PART_NUMBER"TMP_QCS31002JB28"
WATTAGE"1/16W"
CDS_LIB"pure_quanta";
"B"
$PN"2"17;
"A"
$PN"1"1;
%"UNIVERSAL_POWER"
"1","(-4275,5800)","0","pure_quanta_power","I88";
;
HDL_POWER"PVDD18_S5_P1"
CDS_LIB"pure_quanta_power";
"A"1;
%"Q_RES"
"1","(-3975,5275)","0","pure_quanta","I89";
;
LOCATION"R736"
$SEC"1"
CDS_SEC"1"
TOLERANCE"5%"
VALUE"10K"
MATERIAL"EMPTY"
CDS_LIB"pure_quanta"
WATTAGE"1/16W"
PART_NUMBER"TMP_QCS31002JB28"
PACK_TYPE"0402LF";
"B"
$PN"2"16;
"A"
$PN"1"1;
%"Q_RES"
"1","(-8650,3975)","0","pure_quanta","I9";
;
LOCATION"R748"
$SEC"1"
CDS_SEC"1"
MATERIAL"EMPTY"
TOLERANCE"5%"
VALUE"10K"
CDS_LIB"pure_quanta"
WATTAGE"1/16W"
PART_NUMBER"TMP_QCS31002JB28"
PACK_TYPE"0402LF";
"B"
$PN"2"9;
"A"
$PN"1"18;
%"Q_RES"
"1","(-3950,5000)","0","pure_quanta","I90";
;
LOCATION"R1501"
$SEC"1"
CDS_SEC"1"
MATERIAL"EMPTY"
TOLERANCE"5%"
VALUE"10K"
CDS_LIB"pure_quanta"
WATTAGE"1/16W"
PART_NUMBER"TMP_QCS31002JB28"
PACK_TYPE"0402LF";
"B"
$PN"2"15;
"A"
$PN"1"1;
%"Q_RES"
"1","(-3925,4650)","0","pure_quanta","I91";
;
LOCATION"R754"
$SEC"1"
CDS_SEC"1"
PACK_TYPE"0402LF"
PART_NUMBER"TMP_QCS31002JB28"
VALUE"10K"
TOLERANCE"5%"
WATTAGE"1/16W"
MATERIAL"EMPTY"
CDS_LIB"pure_quanta";
"B"
$PN"2"14;
"A"
$PN"1"20;
%"Q_RES"
"1","(-3950,4375)","0","pure_quanta","I92";
;
LOCATION"R760"
$SEC"1"
CDS_SEC"1"
MATERIAL"CHIP"
TOLERANCE"5%"
VALUE"10K"
CDS_LIB"pure_quanta"
WATTAGE"1/16W"
PART_NUMBER"TMP_QCS31002JB28"
PACK_TYPE"0402LF";
"B"
$PN"2"13;
"A"
$PN"1"20;
%"Q_RES"
"1","(-3950,4100)","0","pure_quanta","I94";
;
LOCATION"R1502"
$SEC"1"
CDS_SEC"1"
MATERIAL"CHIP"
TOLERANCE"5%"
VALUE"10K"
CDS_LIB"pure_quanta"
WATTAGE"1/16W"
PART_NUMBER"TMP_QCS31002JB28"
PACK_TYPE"0402LF";
"B"
$PN"2"2;
"A"
$PN"1"20;
%"UNIVERSAL_GND"
"1","(-4275,3725)","0","pure_quanta_power","I95";
;
CDS_LIB"pure_quanta_power"
HDL_POWER"GND";
"A"20;
END.
